FILE_TYPE = CONNECTIVITY;
{Allegro Design Entry HDL 16.6-p007 (v16-6-112F) 10/10/2012}
"PAGE_NUMBER" = 198;
0"NC";
1"GND\g";
2"P5V_STBY\g";
3"GND\g";
4"P5V_STBY\g";
5"P5V_STBY\g";
6"P5V\g";
7"P12V\g";
8"P12V_STBY\g";
9"GND\g";
10"GND\g";
11"GND\g";
12"GND\g";
13"GND\g";
14"GND\g";
15"GND\g";
16"GND\g";
17"GND\g";
18"GND\g";
19"P3V3_STBY\g";
20"GND\g";
21"GND\g";
22"P5V_STBY\g";
23"P3V3\g";
24"GND\g";
25"P12V_STBY\g";
26"GND\g";
27"P12V_FAN\g";
28"P3V3_STBY\g";
29"GND\g";
30"P5V_STBY\g";
31"TP_SLG55021_P12V_MAIN_8";
32"P12V_SWITCH_G"VOLTAGE"+3.3V";
33"FM_P12V_MAIN_SW_EN";
34"FM_CTNR_PS_ON";
35"TP_SLG55021_P5V_8";
36"P5V_SWITCH_G"VOLTAGE"+5V";
37"P12V_FAN_SWITCH_G"VOLTAGE"+5V";
38"TP_SLG55021_P12V_FAN_8";
39"FM_ENABLE_FAN_POWER";
40"P3V3_SWITCH_G"VOLTAGE"3.3";
41"TP_SLG55021_P3V3_8";
42"FM_P3V3_CPLD_EN";
%"SLG55021"
"1","(-7000,3825)","0","mstr_vreg","I1";
;
PACK_TYPE"SM"
CDS_SEC"1"
$SEC"1"
CDS_LOCATION"EU2T1"
ROOM"P3V3_PWR_SWITCH"
CDS_LIB"mstr_vreg"
CDS_LMAN_SYM_OUTLINE"-250,250,250,-250"
LOCATION"EU2T1"
MATERIAL"IC"
PART_NUMBER"G56246-001";
"PG"
$PN"8"41;
"G"
$PN"7"40;
"S"
$PN"6"23;
"D"
$PN"5"19;
"SHDN_N \B"
$PN"3"4;
"ON"
$PN"2"42;
"VCC"
$PN"1"4;
"THPAD"
$PN"9"12;
"GND"
$PN"4"12;
%"GND"
"1","(-2775,3425)","0","mstr_symbols","I12";
;
HDL_POWER"GND"
VOLTAGE"0.0V"
CDS_LIB"mstr_symbols"
SIZE"1B"
BODY_TYPE"PLUMBING";
"A\NAC"1;
%"SLG55021"
"1","(-3300,3800)","0","mstr_vreg","I13";
;
CDS_SEC"1"
SEC_TYPE"SM"
SEC"1"
CDS_LOCATION"EU8B1"
PACK_TYPE"SM"
ROOM"P5V_PWR_SWITCH"
CDS_LMAN_SYM_OUTLINE"-250,250,250,-250"
CDS_LIB"mstr_vreg"
LOCATION"EU8B1"
MATERIAL"IC"
PART_NUMBER"G56246-001";
"PG"
$PN"8"35;
"G"
$PN"7"36;
"S"
$PN"6"6;
"D"
$PN"5"5;
"SHDN_N \B"
$PN"3"30;
"ON"
$PN"2"34;
"VCC"
$PN"1"30;
"THPAD"
$PN"9"1;
"GND"
$PN"4"1;
%"P5V_STBY"
"1","(-7375,2525)","0","mstr_symbols","I15";
;
CDS_LIB"mstr_symbols"
SIZE"1B"
BODY_TYPE"PLUMBING"
VOLTAGE"5.0V"
HDL_POWER"P5V_STBY";
"G\NAC"2;
%"GND"
"1","(-6200,1475)","0","mstr_symbols","I18";
;
SIZE"1B"
HDL_POWER"GND"
VOLTAGE"0.0V"
CDS_LIB"mstr_symbols"
BODY_TYPE"PLUMBING";
"A\NAC"3;
%"SLG55021"
"1","(-6725,1850)","0","mstr_vreg","I19";
;
CDS_SEC"1"
PACK_TYPE"SM"
SEC_TYPE"SM"
SEC"1"
CDS_LOCATION"EU7E1"
ROOM"P12V_PWR_SWITCH"
CDS_LIB"mstr_vreg"
CDS_LMAN_SYM_OUTLINE"-250,250,250,-250"
PART_NUMBER"G56246-001"
LOCATION"EU7E1"
MATERIAL"IC";
"PG"
$PN"8"31;
"G"
$PN"7"32;
"S"
$PN"6"7;
"D"
$PN"5"8;
"SHDN_N \B"
$PN"3"2;
"ON"
$PN"2"33;
"VCC"
$PN"1"2;
"THPAD"
$PN"9"3;
"GND"
$PN"4"3;
%"P5V_STBY"
"1","(-7650,4525)","0","mstr_symbols","I2";
;
CDS_LIB"mstr_symbols"
SIZE"1B"
VOLTAGE"5.0V"
BODY_TYPE"PLUMBING"
HDL_POWER"P5V_STBY";
"G\NAC"4;
%"P5V_STBY"
"1","(-1600,4725)","0","mstr_symbols","I20";
;
BODY_TYPE"PLUMBING"
CDS_LIB"mstr_symbols"
SIZE"1B"
VOLTAGE"5.0V"
HDL_POWER"P5V_STBY";
"G\NAC"5;
%"P5V"
"1","(-1100,3600)","0","mstr_symbols","I21";
;
VOLTAGE"+5.0V"
CDS_LIB"mstr_symbols"
SIZE"1B"
BODY_TYPE"PLUMBING"
HDL_POWER"P5V";
"G\NAC"6;
%"P12V"
"1","(-4675,1625)","0","mstr_symbols","I22";
;
VOLTAGE"+12.0V"
CDS_LIB"mstr_symbols"
SIZE"1B"
BODY_TYPE"PLUMBING"
HDL_POWER"P12V";
"G\NAC"7;
%"P12V_STBY"
"1","(-5325,2575)","0","mstr_symbols","I23";
;
CDS_LIB"mstr_symbols"
SIZE"1B"
VOLTAGE"12.0V"
BODY_TYPE"PLUMBING"
HDL_POWER"P12V_STBY";
"G\NAC"8;
%"CAP_A"
"1","(-8000,4200)","0","dev_discrete","I24";
;
SEC"1"
SEC_TYPE"0402V"
ROOM"P3V3_PWR_SWITCH"
CDS_SEC"1"
CDS_LOCATION"C8F17"
CDS_LIB"dev_discrete"
LOCATION"C8F17"
VALUE"0.1UF"
TOLERANCE"10%"
VOLTAGE"16V"
MATERIAL"X7R"
PART_NUMBER"A36096-030"
PACK_TYPE"0402V";
"B"
$PN"2"9;
"A"
$PN"1"4;
%"GND"
"1","(-8000,4000)","0","mstr_symbols","I25";
;
HDL_POWER"GND"
SIZE"1B"
VOLTAGE"0.0V"
CDS_LIB"mstr_symbols"
BODY_TYPE"PLUMBING";
"A\NAC"9;
%"CAP_A"
"1","(-4300,4125)","0","dev_discrete","I26";
;
SEC"1"
SEC_TYPE"0402V"
CDS_SEC"1"
ROOM"P5V_PWR_SWITCH"
CDS_LIB"dev_discrete"
CDS_LOCATION"C8B8"
LOCATION"C8B8"
PACK_TYPE"0402V"
VALUE"0.1UF"
VOLTAGE"16V"
TOLERANCE"10%"
PART_NUMBER"A36096-030"
MATERIAL"X7R";
"B"
$PN"2"10;
"A"
$PN"1"30;
%"GND"
"1","(-4300,3950)","0","mstr_symbols","I27";
;
HDL_POWER"GND"
CDS_LIB"mstr_symbols"
BODY_TYPE"PLUMBING"
SIZE"1B"
VOLTAGE"0.0V";
"A\NAC"10;
%"CAP_A"
"1","(-7725,2175)","0","dev_discrete","I28";
;
CDS_LOCATION"C8E19"
SEC"1"
SEC_TYPE"0402V"
CDS_SEC"1"
ROOM"P12V_PWR_SWITCH"
CDS_LIB"dev_discrete"
MATERIAL"X7R"
VOLTAGE"16V"
TOLERANCE"10%"
VALUE"0.1UF"
LOCATION"C8E19"
PART_NUMBER"A36096-030"
PACK_TYPE"0402V";
"B"
$PN"2"11;
"A"
$PN"1"2;
%"GND"
"1","(-7725,2000)","0","mstr_symbols","I29";
;
HDL_POWER"GND"
SIZE"1B"
VOLTAGE"0.0V"
CDS_LIB"mstr_symbols"
BODY_TYPE"PLUMBING";
"A\NAC"11;
%"GND"
"1","(-6475,3450)","0","mstr_symbols","I3";
;
HDL_POWER"GND"
BODY_TYPE"PLUMBING"
SIZE"1B"
CDS_LIB"mstr_symbols"
VOLTAGE"0.0V";
"A\NAC"12;
%"CAP_A"
"1","(-1050,4400)","0","dev_discrete","I37";
;
ROOM"P5V_PWR_SWITCH"
CDS_LOCATION"C8B5"
BOM_COST"PWR_SWITCH"
CDS_SEC"1"
SEC_TYPE"0402V"
SEC"1"
CDS_LIB"dev_discrete"
LOCATION"C8B5"
PART_NUMBER"A36096-030"
VALUE"0.1UF"
TOLERANCE"10%"
PACK_TYPE"0402V"
VOLTAGE"16V"
MATERIAL"X7R";
"B"
$PN"2"13;
"A"
$PN"1"5;
%"CAP"
"1","(-1375,4400)","0","mstr_discrete","I38";
;
CDS_SEC"1"
SEC_TYPE"0805"
SEC"1"
CDS_LIB"mstr_discrete"
CDS_LOCATION"C8B12"
ROOM"P5V_PWR_SWITCH"
PART_NUMBER"C95333-007"
MATERIAL"X6S"
PACK_TYPE"0805"
LOCATION"C8B12"
VALUE"10UF"
TOLERANCE"10%"
VOLTAGE"16V";
"A"
$PN"1"5;
"B"
$PN"2"13;
%"GND"
"1","(-1200,4075)","0","mstr_symbols","I39";
;
HDL_POWER"GND"
CDS_LIB"mstr_symbols"
VOLTAGE"0.0V"
SIZE"1B"
BODY_TYPE"PLUMBING";
"A\NAC"13;
%"CAP"
"1","(-1100,3250)","0","mstr_discrete","I40";
;
CDS_SEC"1"
SEC_TYPE"0805"
SEC"1"
ROOM"P5V_PWR_SWITCH"
CDS_LOCATION"C8B6"
CDS_LIB"mstr_discrete"
LOCATION"C8B6"
PART_NUMBER"C95333-007"
VALUE"10UF"
TOLERANCE"10%"
PACK_TYPE"0805"
VOLTAGE"16V"
MATERIAL"X6S";
"A"
$PN"1"6;
"B"
$PN"2"14;
%"CAP_A"
"1","(-775,3250)","0","dev_discrete","I41";
;
BOM_COST"PWR_SWITCH"
SEC"1"
SEC_TYPE"0402V"
CDS_SEC"1"
CDS_LOCATION"C8B7"
ROOM"P5V_PWR_SWITCH"
CDS_LIB"dev_discrete"
LOCATION"C8B7"
PART_NUMBER"A36096-030"
VALUE"0.1UF"
TOLERANCE"10%"
VOLTAGE"16V"
MATERIAL"X7R"
PACK_TYPE"0402V";
"B"
$PN"2"14;
"A"
$PN"1"6;
%"GND"
"1","(-925,2900)","0","mstr_symbols","I42";
;
HDL_POWER"GND"
SIZE"1B"
VOLTAGE"0.0V"
CDS_LIB"mstr_symbols"
BODY_TYPE"PLUMBING";
"A\NAC"14;
%"CAP_A"
"1","(-5050,4275)","0","dev_discrete","I43";
;
BOM_COST"PWR_SWITCH"
SEC"1"
SEC_TYPE"0402V"
CDS_SEC"1"
CDS_LOCATION"C2T36"
ROOM"P3V3_PWR_SWITCH"
CDS_LIB"dev_discrete"
PART_NUMBER"A36096-030"
VALUE"0.1UF"
LOCATION"C2T36"
VOLTAGE"16V"
TOLERANCE"10%"
MATERIAL"X7R"
PACK_TYPE"0402V";
"B"
$PN"2"15;
"A"
$PN"1"19;
%"CAP"
"1","(-5375,4275)","0","mstr_discrete","I44";
;
CDS_SEC"1"
ROOM"P3V3_PWR_SWITCH"
CDS_LOCATION"C2U1"
SEC"1"
SEC_TYPE"0805"
CDS_LIB"mstr_discrete"
TOLERANCE"10%"
MATERIAL"X6S"
PART_NUMBER"C95333-007"
LOCATION"C2U1"
VOLTAGE"16V"
VALUE"10UF"
PACK_TYPE"0805";
"A"
$PN"1"19;
"B"
$PN"2"15;
%"GND"
"1","(-5075,3925)","0","mstr_symbols","I45";
;
HDL_POWER"GND"
CDS_LIB"mstr_symbols"
SIZE"1B"
VOLTAGE"0.0V"
BODY_TYPE"PLUMBING";
"A\NAC"15;
%"CAP_A"
"1","(-4675,3200)","0","dev_discrete","I46";
;
SEC"1"
SEC_TYPE"0402V"
CDS_SEC"1"
BOM_COST"PWR_SWITCH"
ROOM"P3V3_PWR_SWITCH"
CDS_LIB"dev_discrete"
CDS_LOCATION"C2U19"
PART_NUMBER"A36096-030"
LOCATION"C2U19"
VALUE"0.1UF"
TOLERANCE"10%"
VOLTAGE"16V"
MATERIAL"X7R"
PACK_TYPE"0402V";
"B"
$PN"2"16;
"A"
$PN"1"23;
%"CAP"
"1","(-5000,3200)","0","mstr_discrete","I47";
;
CDS_SEC"1"
ROOM"P3V3_PWR_SWITCH"
SEC"1"
SEC_TYPE"0805"
CDS_LOCATION"C2U2"
CDS_LIB"mstr_discrete"
PART_NUMBER"C95333-007"
LOCATION"C2U2"
VALUE"10UF"
TOLERANCE"10%"
VOLTAGE"16V"
MATERIAL"X6S"
PACK_TYPE"0805";
"A"
$PN"1"23;
"B"
$PN"2"16;
%"GND"
"1","(-4775,2850)","0","mstr_symbols","I48";
;
HDL_POWER"GND"
CDS_LIB"mstr_symbols"
VOLTAGE"0.0V"
SIZE"1B"
BODY_TYPE"PLUMBING";
"A\NAC"16;
%"CAP_A"
"1","(-4675,1200)","0","dev_discrete","I49";
;
BOM_COST"PWR_SWITCH"
SEC"1"
SEC_TYPE"0402V"
ROOM"P12V_PWR_SWITCH"
CDS_SEC"1"
CDS_LOCATION"C7E9"
CDS_LIB"dev_discrete"
LOCATION"C7E9"
PART_NUMBER"A36096-030"
VALUE"0.1UF"
TOLERANCE"10%"
VOLTAGE"16V"
MATERIAL"X7R"
PACK_TYPE"0402V";
"B"
$PN"2"17;
"A"
$PN"1"7;
%"CAP"
"1","(-5125,1250)","0","mstr_discrete","I50";
;
CDS_SEC"1"
ROOM"P12V_PWR_SWITCH"
CDS_LOCATION"C7E8"
SEC"1"
SEC_TYPE"0805"
CDS_LIB"mstr_discrete"
PART_NUMBER"C95333-007"
LOCATION"C7E8"
VALUE"10UF"
TOLERANCE"10%"
PACK_TYPE"0805"
VOLTAGE"16V"
MATERIAL"X6S";
"A"
$PN"1"7;
"B"
$PN"2"17;
%"GND"
"1","(-5125,925)","0","mstr_symbols","I51";
;
SIZE"1B"
HDL_POWER"GND"
VOLTAGE"0.0V"
CDS_LIB"mstr_symbols"
BODY_TYPE"PLUMBING";
"A\NAC"17;
%"CAP_A"
"1","(-4775,2250)","0","dev_discrete","I52";
;
BOM_COST"PWR_SWITCH"
SEC"1"
SEC_TYPE"0402V"
CDS_SEC"1"
CDS_LOCATION"C7E5"
ROOM"P12V_PWR_SWITCH"
CDS_LIB"dev_discrete"
PART_NUMBER"A36096-030"
VALUE"0.1UF"
PACK_TYPE"0402V"
LOCATION"C7E5"
TOLERANCE"10%"
VOLTAGE"16V"
MATERIAL"X7R";
"B"
$PN"2"18;
"A"
$PN"1"8;
%"CAP"
"1","(-5100,2250)","0","mstr_discrete","I53";
;
CDS_SEC"1"
SEC_TYPE"0805"
SEC"1"
CDS_LOCATION"C7E6"
ROOM"P12V_PWR_SWITCH"
CDS_LIB"mstr_discrete"
PART_NUMBER"C95333-007"
LOCATION"C7E6"
VALUE"10UF"
PACK_TYPE"0805"
TOLERANCE"10%"
VOLTAGE"16V"
MATERIAL"X6S";
"A"
$PN"1"8;
"B"
$PN"2"18;
%"GND"
"1","(-4800,1900)","0","mstr_symbols","I54";
;
HDL_POWER"GND"
SIZE"1B"
CDS_LIB"mstr_symbols"
BODY_TYPE"PLUMBING"
VOLTAGE"0.0V";
"A\NAC"18;
%"P3V3_STBY"
"1","(-5600,4600)","0","mstr_symbols","I6";
;
SIZE"1B"
CDS_LIB"mstr_symbols"
VOLTAGE"3.3V"
BODY_TYPE"PLUMBING"
HDL_POWER"P3V3_STBY";
"G\NAC"19;
%"CAP"
"1","(-1175,1225)","0","mstr_discrete","I61";
;
CDS_SEC"1"
SEC_TYPE"0805"
SEC"1"
CDS_LOCATION"C1B18"
ROOM"P12V_FAN_PWR_SWITCH"
CDS_LIB"mstr_discrete"
LOCATION"C1B18"
PART_NUMBER"C95333-007"
VALUE"10UF"
PACK_TYPE"0805"
TOLERANCE"10%"
VOLTAGE"16V"
MATERIAL"X6S";
"A"
$PN"1"27;
"B"
$PN"2"20;
%"GND"
"1","(-1175,900)","0","mstr_symbols","I63";
;
HDL_POWER"GND"
SIZE"1B"
CDS_LIB"mstr_symbols"
VOLTAGE"0.0V"
BODY_TYPE"PLUMBING";
"A\NAC"20;
%"CAP_A"
"1","(-725,1225)","0","dev_discrete","I64";
;
BOM_COST"PWR_SWITCH"
ROOM"P12V_FAN_PWR_SWITCH"
SEC_TYPE"0402V"
SEC"1"
CDS_SEC"1"
CDS_LOCATION"C1B19"
CDS_LIB"dev_discrete"
PART_NUMBER"A36096-030"
LOCATION"C1B19"
VALUE"0.1UF"
TOLERANCE"10%"
PACK_TYPE"0402V"
VOLTAGE"16V"
MATERIAL"X7R";
"B"
$PN"2"20;
"A"
$PN"1"27;
%"GND"
"1","(-3775,1950)","0","mstr_symbols","I66";
;
HDL_POWER"GND"
VOLTAGE"0.0V"
SIZE"1B"
CDS_LIB"mstr_symbols"
BODY_TYPE"PLUMBING";
"A\NAC"21;
%"CAP_A"
"1","(-3775,2150)","0","dev_discrete","I67";
;
SEC"1"
SEC_TYPE"0402V"
ROOM"P12V_FAN_PWR_SWITCH"
CDS_SEC"1"
CDS_LIB"dev_discrete"
CDS_LOCATION"C9M6"
LOCATION"C9M6"
VALUE"0.1UF"
MATERIAL"X7R"
VOLTAGE"16V"
TOLERANCE"10%"
PART_NUMBER"A36096-030"
PACK_TYPE"0402V";
"B"
$PN"2"21;
"A"
$PN"1"22;
%"P5V_STBY"
"1","(-3425,2500)","0","mstr_symbols","I68";
;
SIZE"1B"
CDS_LIB"mstr_symbols"
VOLTAGE"5.0V"
BODY_TYPE"PLUMBING"
HDL_POWER"P5V_STBY";
"G\NAC"22;
%"SLG55021"
"1","(-2775,1825)","0","mstr_vreg","I69";
;
CDS_SEC"1"
PACK_TYPE"SM"
SEC_TYPE"SM"
SEC"1"
CDS_LOCATION"EU9M1"
ROOM"P12V_FAN_PWR_SWITCH"
CDS_LMAN_SYM_OUTLINE"-250,250,250,-250"
CDS_LIB"mstr_vreg"
LOCATION"EU9M1"
MATERIAL"IC"
PART_NUMBER"G56246-001";
"PG"
$PN"8"38;
"G"
$PN"7"37;
"S"
$PN"6"27;
"D"
$PN"5"25;
"SHDN_N \B"
$PN"3"22;
"ON"
$PN"2"39;
"VCC"
$PN"1"22;
"THPAD"
$PN"9"24;
"GND"
$PN"4"24;
%"P3V3"
"1","(-5125,3675)","0","mstr_symbols","I7";
;
VOLTAGE"+3.3V"
SIZE"1B"
CDS_LIB"mstr_symbols"
BODY_TYPE"PLUMBING"
HDL_POWER"P3V3";
"G\NAC"23;
%"GND"
"1","(-2250,1450)","0","mstr_symbols","I70";
;
HDL_POWER"GND"
VOLTAGE"0.0V"
SIZE"1B"
CDS_LIB"mstr_symbols"
BODY_TYPE"PLUMBING";
"A\NAC"24;
%"P12V_STBY"
"1","(-1375,2550)","0","mstr_symbols","I73";
;
SIZE"1B"
CDS_LIB"mstr_symbols"
BODY_TYPE"PLUMBING"
VOLTAGE"12.0V"
HDL_POWER"P12V_STBY";
"G\NAC"25;
%"CAP"
"1","(-1150,2225)","0","mstr_discrete","I74";
;
CDS_SEC"1"
ROOM"P12V_FAN_PWR_SWITCH"
CDS_LOCATION"C9M10"
SEC"1"
SEC_TYPE"0805"
CDS_LIB"mstr_discrete"
PART_NUMBER"C95333-007"
MATERIAL"X6S"
LOCATION"C9M10"
PACK_TYPE"0805"
VALUE"10UF"
TOLERANCE"10%"
VOLTAGE"16V";
"A"
$PN"1"25;
"B"
$PN"2"26;
%"GND"
"1","(-850,1900)","0","mstr_symbols","I75";
;
HDL_POWER"GND"
BODY_TYPE"PLUMBING"
SIZE"1B"
CDS_LIB"mstr_symbols"
VOLTAGE"0.0V";
"A\NAC"26;
%"CAP_A"
"1","(-825,2225)","0","dev_discrete","I76";
;
BOM_COST"PWR_SWITCH"
ROOM"P12V_FAN_PWR_SWITCH"
CDS_LOCATION"C9M9"
CDS_SEC"1"
SEC_TYPE"0402V"
SEC"1"
CDS_LIB"dev_discrete"
VALUE"0.1UF"
VOLTAGE"16V"
TOLERANCE"10%"
MATERIAL"X7R"
PART_NUMBER"A36096-030"
LOCATION"C9M9"
PACK_TYPE"0402V";
"B"
$PN"2"26;
"A"
$PN"1"25;
%"P12V_FAN"
"1","(-725,1600)","0","mstr_symbols","I77";
;
HDL_POWER"P12V_FAN"
CDS_LIB"mstr_symbols"
BODY_TYPE"PLUMBING"
VOLTAGE"12.0V";
"G\NAC"27;
%"RES"
"2","(-6925,3050)","0","mstr_discrete","I78";
;
BOM_COST"IO_SLOT"
CDS_SEC"1"
$SEC"1"
CDS_LOCATION"R8E12"
ROOM"IO_SLOT"
CDS_LIB"mstr_discrete"
VALUE"4.75K"
LOCATION"R8E12"
TOLERANCE"1%"
PART_NUMBER"G21796-072"
PACK_TYPE"0402"
MATERIAL"EMPTY"
WATTAGE"1/16W";
"A"
$PN"1"28;
"B"
$PN"2"34;
%"P3V3_STBY"
"1","(-6925,3275)","0","mstr_symbols","I79";
;
SIZE"1B"
VOLTAGE"3.3V"
CDS_LIB"mstr_symbols"
BODY_TYPE"PLUMBING"
HDL_POWER"P3V3_STBY";
"G\NAC"28;
%"RES"
"2","(-6850,2625)","0","mstr_discrete","I83";
;
CDS_SEC"1"
SEC"1"
SEC_TYPE"0402"
ROOM"HOT_SWAP"
CDS_LOCATION"R8B4"
CDS_LIB"mstr_discrete"
PACK_TYPE"0402"
PART_NUMBER"G21796-010"
VALUE"100.0K"
WATTAGE"1/16W"
TOLERANCE"1%"
LOCATION"R8B4"
MATERIAL"CHIP";
"A"
$PN"1"34;
"B"
$PN"2"29;
%"GND"
"1","(-6850,2425)","0","mstr_symbols","I84";
;
HDL_POWER"GND"
SIZE"1B"
BODY_TYPE"PLUMBING"
CDS_LIB"mstr_symbols"
VOLTAGE"0.0V";
"A\NAC"29;
%"MOSFET_N"
"3","(-5650,3900)","2","mstr_discrete","I85";
;
CDS_SEC"1"
CDS_LOCATION"Q8G1"
SEC"1"
SEC_TYPE"LCC3"
PACK_TYPE"LCC3"
CDS_LIB"mstr_discrete"
PART_NUMBER"G26762-001"
VALUE"BSZ019N03LS"
LOCATION"Q8G1"
MATERIAL"NFET";
"DRN"
$PN"5"19;
"SRC"
$PN"1"23;
"GATE"
$PN"4"40;
%"MOSFET_N"
"3","(-1375,1850)","2","mstr_discrete","I86";
;
CDS_SEC"1"
PACK_TYPE"LCC3"
SEC_TYPE"LCC3"
SEC"1"
CDS_LOCATION"Q1B1"
CDS_LIB"mstr_discrete"
PART_NUMBER"G26762-001"
VALUE"BSZ019N03LS"
LOCATION"Q1B1"
MATERIAL"NFET";
"DRN"
$PN"5"25;
"SRC"
$PN"1"27;
"GATE"
$PN"4"37;
%"MOSFET_N"
"3","(-1600,3850)","2","mstr_discrete","I87";
;
CDS_SEC"1"
SEC_TYPE"LCC3"
SEC"1"
CDS_LOCATION"Q8B1"
PACK_TYPE"LCC3"
CDS_LIB"mstr_discrete"
VALUE"BSZ019N03LS"
MATERIAL"NFET"
PART_NUMBER"G26762-001"
LOCATION"Q8B1";
"DRN"
$PN"5"5;
"SRC"
$PN"1"6;
"GATE"
$PN"4"36;
%"MOSFET_N"
"3","(-5325,1850)","2","mstr_discrete","I88";
;
CDS_SEC"1"
SEC_TYPE"LCC3"
SEC"1"
CDS_LOCATION"Q7E7"
CDS_LIB"mstr_discrete"
PACK_TYPE"LCC3"
VALUE"BSZ019N03LS"
LOCATION"Q7E7"
PART_NUMBER"G26762-001"
MATERIAL"NFET";
"DRN"
$PN"5"8;
"SRC"
$PN"1"7;
"GATE"
$PN"4"32;
%"P5V_STBY"
"1","(-3950,4350)","0","mstr_symbols","I9";
;
SIZE"1B"
CDS_LIB"mstr_symbols"
VOLTAGE"5.0V"
BODY_TYPE"PLUMBING"
HDL_POWER"P5V_STBY";
"G\NAC"30;
END.
